#ISCELL
  mstr_misc dns *
  *
#ISCELL
  pure_quanta quanta_title_block_c *
  *
#ISCELL
  logical_power universal_gnd *
  page267_i1
#CELL
  pure_quanta q_cap *
  page267_i10
#ISCELL
  logical_power universal_gnd *
  page267_i11
#CELL
  pure_quanta q_cap *
  page267_i12
#ISCELL
  logical_power universal_gnd *
  page267_i13
#CELL
  pure_quanta q_res *
  page267_i14
#CELL
  pure_quanta q_res *
  page267_i15
#CELL
  pure_quanta q_cap *
  page267_i16
#CELL
  pure_quanta q_cap *
  page267_i17
#CELL
  pure_quanta q_res *
  page267_i18
#CELL
  pure_quanta rs53318lr *
  page267_i19
#ISCELL
  standard offpage *
  page267_i2
#ISCELL
  logical_power universal_gnd *
  page267_i20
#ISCELL
  logical_power vccaux15 *
  page267_i21
#ISCELL
  logical_power universal_gnd *
  page267_i22
#CELL
  pure_quanta q_cap *
  page267_i23
#ISCELL
  logical_power universal_gnd *
  page267_i24
#CELL
  pure_quanta q_cap *
  page267_i25
#CELL
  pure_quanta q_res *
  page267_i26
#CELL
  pure_quanta q_cap *
  page267_i27
#CELL
  pure_quanta q_inductor *
  page267_i28
#CELL
  pure_quanta q_res *
  page267_i29
#ISCELL
  logical_power vccaux15 *
  page267_i3
#CELL
  pure_quanta q_cap *
  page267_i30
#CELL
  pure_quanta mosfet_n *
  page267_i31
#ISCELL
  standard offpage *
  page267_i32
#CELL
  pure_quanta q_short *
  page267_i33
#CELL
  pure_quanta q_res *
  page267_i34
#CELL
  pure_quanta q_cap *
  page267_i35
#CELL
  pure_quanta q_res *
  page267_i36
#ISCELL
  logical_power universal_gnd *
  page267_i37
#CELL
  pure_quanta q_cap *
  page267_i38
#ISCELL
  standard offpage *
  page267_i39
#CELL
  pure_quanta q_cap *
  page267_i4
#CELL
  pure_quanta q_cap *
  page267_i40
#CELL
  pure_quanta q_short *
  page267_i41
#CELL
  pure_quanta q_cap *
  page267_i42
#CELL
  pure_quanta q_cap *
  page267_i43
#CELL
  pure_quanta q_cap *
  page267_i44
#CELL
  pure_quanta q_res *
  page267_i45
#ISCELL
  logical_power universal_power *
  page267_i46
#ISCELL
  logical_power universal_gnd *
  page267_i47
#ISCELL
  logical_power universal_gnd *
  page267_i48
#CELL
  pure_quanta q_capp *
  page267_i49
#CELL
  pure_quanta q_res *
  page267_i5
#ISCELL
  logical_power universal_power *
  page267_i50
#ISCELL
  logical_power universal_power *
  page267_i6
#CELL
  pure_quanta q_cap *
  page267_i7
#ISCELL
  logical_power universal_gnd *
  page267_i8
#CELL
  pure_quanta q_res *
  page267_i9
